(kicad_pcb
	(version 20260206)
	(generator "pcbnew")
	(generator_version "10.0")
	(general
		(thickness 1.6)
		(legacy_teardrops no)
	)
	(paper "A4")
	(title_block
		(title "v2-pdb — ms_pdb_v2.brd")
		(comment 1 "Open CloudServer (Microsoft) / footprint 334 of 348 (J17), pads 1-46 of 46")
	)
	(layers
		(0 "F.Cu" signal "TOP")
		(4 "In1.Cu" signal "GND")
		(6 "In2.Cu" signal "IN1")
		(8 "In3.Cu" signal "VCC")
		(10 "In4.Cu" signal "VCC1")
		(12 "In5.Cu" signal "IN2")
		(14 "In6.Cu" signal "GND1")
		(2 "B.Cu" signal "BOTTOM")
		(9 "F.Adhes" user "F.Adhesive")
		(11 "B.Adhes" user "B.Adhesive")
		(13 "F.Paste" user "Package Geometry/Pastemask Top")
		(15 "B.Paste" user "Package Geometry/Pastemask Bottom")
		(5 "F.SilkS" user "Ref Des/Silkscreen Top")
		(7 "B.SilkS" user "Ref Des/Silkscreen Bottom")
		(1 "F.Mask" user "Board Geometry/Soldermask Top")
		(3 "B.Mask" user "Board Geometry/Soldermask Bottom")
		(17 "Dwgs.User" user "User.Drawings")
		(19 "Cmts.User" user "User.Comments")
		(21 "Eco1.User" user "User.Eco1")
		(23 "Eco2.User" user "User.Eco2")
		(25 "Edge.Cuts" user "Board Geometry/Outline")
		(27 "Margin" user)
		(31 "F.CrtYd" user "Package Geometry/Place Bound Top")
		(29 "B.CrtYd" user "Package Geometry/Place Bound Bottom")
		(35 "F.Fab" user "Ref Des/Assembly Top")
		(33 "B.Fab" user "Ref Des/Assembly Bottom")
	)
	(footprint ""
		(layer "B.Cu")
		(at 44.03979 -452.76008 90)
		(property "Reference" "J17"
			(at 6.342888 1.323848 0)
			(unlocked yes)
			(layer "B.SilkS")
			(effects
				(font
					(size 0.7874 0.5842)
					(thickness 0.1524)
				)
				(justify left mirror)
			)
		)
		(property "Value" ""
			(at 0 0 90)
			(layer "B.Fab")
			(effects
				(font
					(size 1.27 1.27)
				)
				(justify mirror)
			)
		)
		(duplicate_pad_numbers_are_jumpers no)
		(pad "" np_thru_hole circle
			(at -1.35001 -2.54)
			(size 2.5146 2.5146)
			(drill 2.5146)
			(layers "*.Cu" "*.Mask")
			(clearance 0.381)
			(thermal_gap 0.381)
		)
		(pad "" np_thru_hole circle
			(at 0 50.8)
			(size 2.5146 2.5146)
			(drill 2.5146)
			(layers "*.Cu" "*.Mask")
			(clearance 0.381)
			(thermal_gap 0.381)
		)
		(pad "P1" thru_hole rect
			(at 0 0)
			(size 1.1684 1.1684)
			(drill 0.762)
			(layers "*.Cu" "*.Mask")
			(remove_unused_layers no)
			(net "GND")
			(clearance 0.0508)
			(padstack
				(mode front_inner_back)
				(layer "Inner"
					(shape circle)
					(size 1.1684 1.1684)
					(clearance 0.0508)
				)
				(layer "B.Cu"
					(shape rect)
					(size 1.1684 1.1684)
					(thermal_gap 0.0508)
					(clearance 0.0508)
				)
			)
		)
		(pad "P2" thru_hole circle
			(at 0 2.54)
			(size 1.1684 1.1684)
			(drill 0.762)
			(layers "*.Cu" "*.Mask")
			(remove_unused_layers no)
			(net "GND")
			(clearance 0.0508)
			(thermal_gap 0.0508)
		)
		(pad "P3" thru_hole circle
			(at 0 5.08)
			(size 1.1684 1.1684)
			(drill 0.762)
			(layers "*.Cu" "*.Mask")
			(remove_unused_layers no)
			(net "GND")
			(clearance 0.0508)
			(thermal_gap 0.0508)
		)
		(pad "P4" thru_hole circle
			(at 0 7.62)
			(size 1.1684 1.1684)
			(drill 0.762)
			(layers "*.Cu" "*.Mask")
			(remove_unused_layers no)
			(net "GND")
			(clearance 0.0508)
			(thermal_gap 0.0508)
		)
		(pad "P5" thru_hole circle
			(at 0 10.16)
			(size 1.1684 1.1684)
			(drill 0.762)
			(layers "*.Cu" "*.Mask")
			(remove_unused_layers no)
			(net "GND")
			(clearance 0.0508)
			(thermal_gap 0.0508)
		)
		(pad "P6" thru_hole circle
			(at 0 12.7)
			(size 1.1684 1.1684)
			(drill 0.762)
			(layers "*.Cu" "*.Mask")
			(remove_unused_layers no)
			(net "GND")
			(clearance 0.0508)
			(thermal_gap 0.0508)
		)
		(pad "P7" thru_hole circle
			(at 0 15.24)
			(size 1.1684 1.1684)
			(drill 0.762)
			(layers "*.Cu" "*.Mask")
			(remove_unused_layers no)
			(net "GND")
			(clearance 0.0508)
			(thermal_gap 0.0508)
		)
		(pad "P8" thru_hole circle
			(at 0 17.78)
			(size 1.1684 1.1684)
			(drill 0.762)
			(layers "*.Cu" "*.Mask")
			(remove_unused_layers no)
			(net "GND")
			(clearance 0.0508)
			(thermal_gap 0.0508)
		)
		(pad "P9" thru_hole circle
			(at 0 20.32)
			(size 1.1684 1.1684)
			(drill 0.762)
			(layers "*.Cu" "*.Mask")
			(remove_unused_layers no)
			(net "P12V")
			(clearance 0.0508)
			(thermal_gap 0.0508)
		)
		(pad "P10" thru_hole circle
			(at 0 22.86)
			(size 1.1684 1.1684)
			(drill 0.762)
			(layers "*.Cu" "*.Mask")
			(remove_unused_layers no)
			(net "P12V")
			(clearance 0.0508)
			(thermal_gap 0.0508)
		)
		(pad "P11" thru_hole circle
			(at 0 25.4)
			(size 1.1684 1.1684)
			(drill 0.762)
			(layers "*.Cu" "*.Mask")
			(remove_unused_layers no)
			(net "P12V")
			(clearance 0.0508)
			(thermal_gap 0.0508)
		)
		(pad "P12" thru_hole circle
			(at 0 27.94)
			(size 1.1684 1.1684)
			(drill 0.762)
			(layers "*.Cu" "*.Mask")
			(remove_unused_layers no)
			(net "P12V")
			(clearance 0.0508)
			(thermal_gap 0.0508)
		)
		(pad "P13" thru_hole circle
			(at 0 30.48)
			(size 1.1684 1.1684)
			(drill 0.762)
			(layers "*.Cu" "*.Mask")
			(remove_unused_layers no)
			(net "P12V")
			(clearance 0.0508)
			(thermal_gap 0.0508)
		)
		(pad "P14" thru_hole circle
			(at 0 33.02)
			(size 1.1684 1.1684)
			(drill 0.762)
			(layers "*.Cu" "*.Mask")
			(remove_unused_layers no)
			(net "P12V")
			(clearance 0.0508)
			(thermal_gap 0.0508)
		)
		(pad "P15" thru_hole circle
			(at 0 35.56)
			(size 1.1684 1.1684)
			(drill 0.762)
			(layers "*.Cu" "*.Mask")
			(remove_unused_layers no)
			(net "P12V")
			(clearance 0.0508)
			(thermal_gap 0.0508)
		)
		(pad "P16" thru_hole circle
			(at 0 38.1)
			(size 1.1684 1.1684)
			(drill 0.762)
			(layers "*.Cu" "*.Mask")
			(remove_unused_layers no)
			(net "P12V")
			(clearance 0.0508)
			(thermal_gap 0.0508)
		)
		(pad "P17" thru_hole circle
			(at -2.70002 38.1)
			(size 1.1684 1.1684)
			(drill 0.762)
			(layers "*.Cu" "*.Mask")
			(remove_unused_layers no)
			(net "P12V")
			(clearance 0.0508)
			(thermal_gap 0.0508)
		)
		(pad "P18" thru_hole circle
			(at -2.70002 35.56)
			(size 1.1684 1.1684)
			(drill 0.762)
			(layers "*.Cu" "*.Mask")
			(remove_unused_layers no)
			(net "P12V")
			(clearance 0.0508)
			(thermal_gap 0.0508)
		)
		(pad "P19" thru_hole circle
			(at -2.70002 33.02)
			(size 1.1684 1.1684)
			(drill 0.762)
			(layers "*.Cu" "*.Mask")
			(remove_unused_layers no)
			(net "P12V")
			(clearance 0.0508)
			(thermal_gap 0.0508)
		)
		(pad "P20" thru_hole circle
			(at -2.70002 30.48)
			(size 1.1684 1.1684)
			(drill 0.762)
			(layers "*.Cu" "*.Mask")
			(remove_unused_layers no)
			(net "P12V")
			(clearance 0.0508)
			(thermal_gap 0.0508)
		)
		(pad "P21" thru_hole circle
			(at -2.70002 27.94)
			(size 1.1684 1.1684)
			(drill 0.762)
			(layers "*.Cu" "*.Mask")
			(remove_unused_layers no)
			(net "P12V")
			(clearance 0.0508)
			(thermal_gap 0.0508)
		)
		(pad "P22" thru_hole circle
			(at -2.70002 25.4)
			(size 1.1684 1.1684)
			(drill 0.762)
			(layers "*.Cu" "*.Mask")
			(remove_unused_layers no)
			(net "P12V")
			(clearance 0.0508)
			(thermal_gap 0.0508)
		)
		(pad "P23" thru_hole circle
			(at -2.70002 22.86)
			(size 1.1684 1.1684)
			(drill 0.762)
			(layers "*.Cu" "*.Mask")
			(remove_unused_layers no)
			(net "P12V")
			(clearance 0.0508)
			(thermal_gap 0.0508)
		)
		(pad "P24" thru_hole circle
			(at -2.70002 20.32)
			(size 1.1684 1.1684)
			(drill 0.762)
			(layers "*.Cu" "*.Mask")
			(remove_unused_layers no)
			(net "P12V")
			(clearance 0.0508)
			(thermal_gap 0.0508)
		)
		(pad "P25" thru_hole circle
			(at -2.70002 17.78)
			(size 1.1684 1.1684)
			(drill 0.762)
			(layers "*.Cu" "*.Mask")
			(remove_unused_layers no)
			(net "GND")
			(clearance 0.0508)
			(thermal_gap 0.0508)
		)
		(pad "P26" thru_hole circle
			(at -2.70002 15.24)
			(size 1.1684 1.1684)
			(drill 0.762)
			(layers "*.Cu" "*.Mask")
			(remove_unused_layers no)
			(net "GND")
			(clearance 0.0508)
			(thermal_gap 0.0508)
		)
		(pad "P27" thru_hole circle
			(at -2.70002 12.7)
			(size 1.1684 1.1684)
			(drill 0.762)
			(layers "*.Cu" "*.Mask")
			(remove_unused_layers no)
			(net "GND")
			(clearance 0.0508)
			(thermal_gap 0.0508)
		)
		(pad "P28" thru_hole circle
			(at -2.70002 10.16)
			(size 1.1684 1.1684)
			(drill 0.762)
			(layers "*.Cu" "*.Mask")
			(remove_unused_layers no)
			(net "GND")
			(clearance 0.0508)
			(thermal_gap 0.0508)
		)
		(pad "P29" thru_hole circle
			(at -2.70002 7.62)
			(size 1.1684 1.1684)
			(drill 0.762)
			(layers "*.Cu" "*.Mask")
			(remove_unused_layers no)
			(net "GND")
			(clearance 0.0508)
			(thermal_gap 0.0508)
		)
		(pad "P30" thru_hole circle
			(at -2.70002 5.08)
			(size 1.1684 1.1684)
			(drill 0.762)
			(layers "*.Cu" "*.Mask")
			(remove_unused_layers no)
			(net "GND")
			(clearance 0.0508)
			(thermal_gap 0.0508)
		)
		(pad "P31" thru_hole circle
			(at -2.70002 2.54)
			(size 1.1684 1.1684)
			(drill 0.762)
			(layers "*.Cu" "*.Mask")
			(remove_unused_layers no)
			(net "GND")
			(clearance 0.0508)
			(thermal_gap 0.0508)
		)
		(pad "P32" thru_hole circle
			(at -2.70002 0)
			(size 1.1684 1.1684)
			(drill 0.762)
			(layers "*.Cu" "*.Mask")
			(remove_unused_layers no)
			(net "GND")
			(clearance 0.0508)
			(thermal_gap 0.0508)
		)
		(pad "S1" thru_hole circle
			(at 0.55499 41.60012)
			(size 1.1684 1.1684)
			(drill 0.762)
			(layers "*.Cu" "*.Mask")
			(remove_unused_layers no)
			(net "T11_BLAD1_TXD")
			(clearance 0.0508)
			(thermal_gap 0.0508)
		)
		(pad "S2" thru_hole circle
			(at -0.71501 42.87012)
			(size 1.1684 1.1684)
			(drill 0.762)
			(layers "*.Cu" "*.Mask")
			(remove_unused_layers no)
			(net "T11_BLAD1_RXD")
			(clearance 0.0508)
			(thermal_gap 0.0508)
		)
		(pad "S3" thru_hole circle
			(at 0.55499 44.14012)
			(size 1.1684 1.1684)
			(drill 0.762)
			(layers "*.Cu" "*.Mask")
			(remove_unused_layers no)
			(net "T11_BLAD1_EN")
			(clearance 0.0508)
			(thermal_gap 0.0508)
		)
		(pad "S4" thru_hole circle
			(at -0.71501 45.41012)
			(size 1.1684 1.1684)
			(drill 0.762)
			(layers "*.Cu" "*.Mask")
			(remove_unused_layers no)
			(net "B21_PSU_ALERT_N")
			(clearance 0.0508)
			(thermal_gap 0.0508)
		)
		(pad "S5" thru_hole circle
			(at 0.55499 46.68012)
			(size 1.1684 1.1684)
			(drill 0.762)
			(layers "*.Cu" "*.Mask")
			(remove_unused_layers no)
			(net "T11_BLAD2_TXD")
			(clearance 0.0508)
			(thermal_gap 0.0508)
		)
		(pad "S6" thru_hole circle
			(at -0.71501 47.95012)
			(size 1.1684 1.1684)
			(drill 0.762)
			(layers "*.Cu" "*.Mask")
			(remove_unused_layers no)
			(net "T11_BLAD2_RXD")
			(clearance 0.0508)
			(thermal_gap 0.0508)
		)
		(pad "S7" thru_hole circle
			(at -3.25501 47.95012)
			(size 1.1684 1.1684)
			(drill 0.762)
			(layers "*.Cu" "*.Mask")
			(remove_unused_layers no)
			(net "T11_BLAD4_RXD")
			(clearance 0.0508)
			(thermal_gap 0.0508)
		)
		(pad "S8" thru_hole circle
			(at -1.98501 46.68012)
			(size 1.1684 1.1684)
			(drill 0.762)
			(layers "*.Cu" "*.Mask")
			(remove_unused_layers no)
			(net "T11_BLAD4_TXD")
			(clearance 0.0508)
			(thermal_gap 0.0508)
		)
		(pad "S9" thru_hole circle
			(at -3.25501 45.41012)
			(size 1.1684 1.1684)
			(drill 0.762)
			(layers "*.Cu" "*.Mask")
			(remove_unused_layers no)
			(net "B22_PSU_ALERT_N")
			(clearance 0.0508)
			(thermal_gap 0.0508)
		)
		(pad "S10" thru_hole circle
			(at -1.98501 44.14012)
			(size 1.1684 1.1684)
			(drill 0.762)
			(layers "*.Cu" "*.Mask")
			(remove_unused_layers no)
			(net "T11_BLAD3_EN")
			(clearance 0.0508)
			(thermal_gap 0.0508)
		)
		(pad "S11" thru_hole circle
			(at -3.25501 42.87012)
			(size 1.1684 1.1684)
			(drill 0.762)
			(layers "*.Cu" "*.Mask")
			(remove_unused_layers no)
			(net "T11_BLAD3_RXD")
			(clearance 0.0508)
			(thermal_gap 0.0508)
		)
		(pad "S12" thru_hole circle
			(at -1.98501 41.60012)
			(size 1.1684 1.1684)
			(drill 0.762)
			(layers "*.Cu" "*.Mask")
			(remove_unused_layers no)
			(net "T11_BLAD3_TXD")
			(clearance 0.0508)
			(thermal_gap 0.0508)
		)
	)
)
